(kicad_pcb
	(version 20260206)
	(generator "pcbnew")
	(generator_version "10.0")
	(general
		(thickness 1.6)
		(legacy_teardrops no)
	)
	(paper "A4")
	(title_block
		(title "Bryce Canyon_IOM_M2_16342-2_OCP.brd")
		(comment 1 "Bryce Canyon / footprints 349-355 of 1146")
	)
	(layers
		(0 "F.Cu" signal "TOP")
		(4 "In1.Cu" signal "L2GND")
		(6 "In2.Cu" signal "L3")
		(8 "In3.Cu" signal "L4VCC")
		(10 "In4.Cu" signal "L5VCC")
		(12 "In5.Cu" signal "L6")
		(14 "In6.Cu" signal "L7GND")
		(2 "B.Cu" signal "BOTTOM")
		(9 "F.Adhes" user "F.Adhesive")
		(11 "B.Adhes" user "B.Adhesive")
		(13 "F.Paste" user "Package Geometry/Pastemask Top")
		(15 "B.Paste" user "Package Geometry/Pastemask Bottom")
		(5 "F.SilkS" user "Ref Des/Silkscreen Top")
		(7 "B.SilkS" user "Ref Des/Silkscreen Bottom")
		(1 "F.Mask" user "Board Geometry/Soldermask Top")
		(3 "B.Mask" user "Board Geometry/Soldermask Bottom")
		(17 "Dwgs.User" user "User.Drawings")
		(19 "Cmts.User" user "User.Comments")
		(21 "Eco1.User" user "User.Eco1")
		(23 "Eco2.User" user "User.Eco2")
		(25 "Edge.Cuts" user "Board Geometry/Outline")
		(27 "Margin" user)
		(31 "F.CrtYd" user "Package Geometry/Place Bound Top")
		(29 "B.CrtYd" user "Package Geometry/Place Bound Bottom")
		(35 "F.Fab" user "Ref Des/Assembly Top")
		(33 "B.Fab" user "Ref Des/Assembly Bottom")
	)
	(footprint ""
		(layer "F.Cu")
		(at 61.289184 -142.341092 90)
		(property "Reference" "R157"
			(at 0 0 90)
			(layer "F.SilkS")
			(hide yes)
			(effects
				(font
					(size 1.27 1.27)
				)
			)
		)
		(property "Value" "0R2J-2-GP"
			(at 0.064008 -3.993896 90)
			(unlocked yes)
			(layer "F.Fab")
			(hide yes)
			(effects
				(font
					(size 1.016 1.016)
					(thickness 0.1524)
				)
			)
		)
		(property "Device Type" "R402H16"
			(at 0.064008 -5.517896 90)
			(unlocked yes)
			(layer "F.Fab")
			(hide yes)
			(effects
				(font
					(size 1.016 1.016)
					(thickness 0.1524)
				)
			)
		)
		(duplicate_pad_numbers_are_jumpers no)
		(fp_line
			(start 0.508 -0.9398)
			(end -0.508 -0.9398)
			(stroke
				(width 0.1524)
				(type default)
			)
			(layer "F.SilkS")
		)
		(fp_line
			(start -0.508 -0.9398)
			(end -0.508 0.9398)
			(stroke
				(width 0.1524)
				(type default)
			)
			(layer "F.SilkS")
		)
		(fp_rect
			(start -0.508 0.9398)
			(end 0.508 -0.9398)
			(stroke
				(width 0)
				(type default)
			)
			(fill no)
			(layer "F.CrtYd")
		)
		(fp_rect
			(start -0.508 0.9398)
			(end 0.508 -0.9398)
			(stroke
				(width 0)
				(type default)
			)
			(fill no)
			(layer "F.Fab")
		)
		(pad "1" smd custom
			(at 0 -0.4445 90)
			(size 0.1397 0.1397)
			(layers "F.Cu" "F.Mask" "F.Paste")
			(net "BMC_SMB11_DAT")
			(options
				(clearance outline)
				(anchor circle)
			)
			(primitives
				(gr_poly
					(pts
						(arc
							(start -0.1778 -0.2794)
							(mid -0.249642 -0.249642)
							(end -0.2794 -0.1778)
						)
						(arc
							(start -0.2794 0.1778)
							(mid -0.249642 0.249642)
							(end -0.1778 0.2794)
						)
						(arc
							(start 0.1778 0.2794)
							(mid 0.249642 0.249642)
							(end 0.2794 0.1778)
						)
						(arc
							(start 0.2794 -0.1778)
							(mid 0.249642 -0.249642)
							(end 0.1778 -0.2794)
						)
					)
					(width 0)
					(fill yes)
				)
			)
		)
		(pad "2" smd custom
			(at 0 0.4445 90)
			(size 0.1397 0.1397)
			(layers "F.Cu" "F.Mask" "F.Paste")
			(net "I2C_EXP_RMT_SDA_OUT")
			(options
				(clearance outline)
				(anchor circle)
			)
			(primitives
				(gr_poly
					(pts
						(arc
							(start -0.1778 -0.2794)
							(mid -0.249642 -0.249642)
							(end -0.2794 -0.1778)
						)
						(arc
							(start -0.2794 0.1778)
							(mid -0.249642 0.249642)
							(end -0.1778 0.2794)
						)
						(arc
							(start 0.1778 0.2794)
							(mid 0.249642 0.249642)
							(end 0.2794 0.1778)
						)
						(arc
							(start 0.2794 -0.1778)
							(mid 0.249642 -0.249642)
							(end 0.1778 -0.2794)
						)
					)
					(width 0)
					(fill yes)
				)
			)
		)
	)
	(footprint ""
		(layer "F.Cu")
		(at 42.988738 -185.10885 90)
		(property "Reference" "L9"
			(at 0 0 90)
			(layer "F.SilkS")
			(hide yes)
			(effects
				(font
					(size 1.27 1.27)
				)
			)
		)
		(property "Value" "COIL-3D3UH-26-GP"
			(at -4.699 -4.0132 90)
			(unlocked yes)
			(layer "F.Fab")
			(hide yes)
			(effects
				(font
					(size 1.016 1.016)
					(thickness 0.1524)
				)
			)
		)
		(property "Device Type" "L7066-1830-UH119"
			(at -4.699 -5.5372 90)
			(unlocked yes)
			(layer "F.Fab")
			(hide yes)
			(effects
				(font
					(size 1.016 1.016)
					(thickness 0.1524)
				)
			)
		)
		(duplicate_pad_numbers_are_jumpers no)
		(fp_line
			(start 3.556 -4.4958)
			(end 3.556 4.4958)
			(stroke
				(width 0.1524)
				(type default)
			)
			(layer "F.SilkS")
		)
		(fp_line
			(start -3.556 -4.4958)
			(end 3.556 -4.4958)
			(stroke
				(width 0.1524)
				(type default)
			)
			(layer "F.SilkS")
		)
		(fp_line
			(start 3.556 4.4958)
			(end -3.556 4.4958)
			(stroke
				(width 0.1524)
				(type default)
			)
			(layer "F.SilkS")
		)
		(fp_line
			(start -3.556 4.4958)
			(end -3.556 -4.4958)
			(stroke
				(width 0.1524)
				(type default)
			)
			(layer "F.SilkS")
		)
		(fp_rect
			(start -3.302 3.4798)
			(end 3.302 -3.4798)
			(stroke
				(width 0)
				(type default)
			)
			(fill no)
			(layer "F.CrtYd")
		)
		(fp_poly
			(pts
				(xy -3.81 4.572) (xy -3.81 -4.572) (xy 3.81 -4.572) (xy 3.81 -0.5588) (xy 3.302 -0.5588) (xy 3.302 -3.4798)
				(xy -3.302 -3.4798) (xy -3.302 3.4798) (xy 3.302 3.4798) (xy 3.302 -0.5461) (xy 3.81 -0.5461) (xy 3.81 4.572)
			)
			(stroke
				(width 0)
				(type default)
			)
			(fill no)
			(layer "F.CrtYd")
		)
		(fp_rect
			(start -3.81 4.572)
			(end 3.81 -4.572)
			(stroke
				(width 0)
				(type default)
			)
			(fill no)
			(layer "F.Fab")
		)
		(pad "1" smd rect
			(at 0 -2.779522 90)
			(size 3.5052 2.921)
			(layers "F.Cu" "F.Mask" "F.Paste")
			(net "P3V3_STBY_LL")
		)
		(pad "2" smd rect
			(at 0 2.779522 90)
			(size 3.5052 2.921)
			(layers "F.Cu" "F.Mask" "F.Paste")
			(net "P3V3_STBY_OUT")
		)
	)
	(footprint ""
		(layer "F.Cu")
		(at 98.942144 -156.96692 -90)
		(property "Reference" "R18"
			(at 0 0 270)
			(layer "F.SilkS")
			(hide yes)
			(effects
				(font
					(size 1.27 1.27)
				)
			)
		)
		(property "Value" "4K7R2F-GP"
			(at 0.064008 -3.993896 270)
			(unlocked yes)
			(layer "F.Fab")
			(hide yes)
			(effects
				(font
					(size 1.016 1.016)
					(thickness 0.1524)
				)
			)
		)
		(property "Device Type" "R402H16"
			(at 0.064008 -5.517896 270)
			(unlocked yes)
			(layer "F.Fab")
			(hide yes)
			(effects
				(font
					(size 1.016 1.016)
					(thickness 0.1524)
				)
			)
		)
		(duplicate_pad_numbers_are_jumpers no)
		(fp_line
			(start -0.508 -0.9398)
			(end -0.508 0.9398)
			(stroke
				(width 0.1524)
				(type default)
			)
			(layer "F.SilkS")
		)
		(fp_line
			(start 0.508 -0.9398)
			(end -0.508 -0.9398)
			(stroke
				(width 0.1524)
				(type default)
			)
			(layer "F.SilkS")
		)
		(fp_rect
			(start -0.508 0.9398)
			(end 0.508 -0.9398)
			(stroke
				(width 0)
				(type default)
			)
			(fill no)
			(layer "F.CrtYd")
		)
		(fp_rect
			(start -0.508 0.9398)
			(end 0.508 -0.9398)
			(stroke
				(width 0)
				(type default)
			)
			(fill no)
			(layer "F.Fab")
		)
		(pad "1" smd custom
			(at 0 -0.4445 270)
			(size 0.1397 0.1397)
			(layers "F.Cu" "F.Mask" "F.Paste")
			(net "P3V3_STBY")
			(options
				(clearance outline)
				(anchor circle)
			)
			(primitives
				(gr_poly
					(pts
						(arc
							(start -0.1778 -0.2794)
							(mid -0.249642 -0.249642)
							(end -0.2794 -0.1778)
						)
						(arc
							(start -0.2794 0.1778)
							(mid -0.249642 0.249642)
							(end -0.1778 0.2794)
						)
						(arc
							(start 0.1778 0.2794)
							(mid 0.249642 0.249642)
							(end 0.2794 0.1778)
						)
						(arc
							(start 0.2794 -0.1778)
							(mid 0.249642 -0.249642)
							(end 0.1778 -0.2794)
						)
					)
					(width 0)
					(fill yes)
				)
			)
		)
		(pad "2" smd custom
			(at 0 0.4445 270)
			(size 0.1397 0.1397)
			(layers "F.Cu" "F.Mask" "F.Paste")
			(net "CFG_SEL1")
			(options
				(clearance outline)
				(anchor circle)
			)
			(primitives
				(gr_poly
					(pts
						(arc
							(start -0.1778 -0.2794)
							(mid -0.249642 -0.249642)
							(end -0.2794 -0.1778)
						)
						(arc
							(start -0.2794 0.1778)
							(mid -0.249642 0.249642)
							(end -0.1778 0.2794)
						)
						(arc
							(start 0.1778 0.2794)
							(mid 0.249642 0.249642)
							(end 0.2794 0.1778)
						)
						(arc
							(start 0.2794 -0.1778)
							(mid 0.249642 -0.249642)
							(end 0.1778 -0.2794)
						)
					)
					(width 0)
					(fill yes)
				)
			)
		)
	)
	(footprint ""
		(layer "F.Cu")
		(at 91.613228 -47.034196 -90)
		(property "Reference" "C219"
			(at 0 0 270)
			(layer "F.SilkS")
			(hide yes)
			(effects
				(font
					(size 1.27 1.27)
				)
			)
		)
		(property "Value" "SCD47U25V3KX-3-GP"
			(at 0 -2.8194 270)
			(unlocked yes)
			(layer "F.Fab")
			(hide yes)
			(effects
				(font
					(size 1.016 1.016)
					(thickness 0.1524)
				)
			)
		)
		(property "Device Type" "C603H36"
			(at 0 -4.3434 270)
			(unlocked yes)
			(layer "F.Fab")
			(hide yes)
			(effects
				(font
					(size 1.016 1.016)
					(thickness 0.1524)
				)
			)
		)
		(duplicate_pad_numbers_are_jumpers no)
		(fp_line
			(start 0.508 0)
			(end -0.508 0)
			(stroke
				(width 0.2032)
				(type default)
			)
			(layer "F.SilkS")
		)
		(fp_rect
			(start -0.5842 1.3335)
			(end 0.5842 -1.3335)
			(stroke
				(width 0)
				(type default)
			)
			(fill no)
			(layer "F.CrtYd")
		)
		(fp_rect
			(start -0.5842 1.3335)
			(end 0.5842 -1.3335)
			(stroke
				(width 0)
				(type default)
			)
			(fill no)
			(layer "F.Fab")
		)
		(pad "1" smd custom
			(at 0 -0.762 270)
			(size 0.2159 0.2159)
			(layers "F.Cu" "F.Mask" "F.Paste")
			(net "PQ2_D")
			(options
				(clearance outline)
				(anchor circle)
			)
			(primitives
				(gr_poly
					(pts
						(arc
							(start -0.3302 -0.4318)
							(mid -0.402042 -0.402042)
							(end -0.4318 -0.3302)
						)
						(arc
							(start -0.4318 0.3302)
							(mid -0.402042 0.402042)
							(end -0.3302 0.4318)
						)
						(arc
							(start 0.3302 0.4318)
							(mid 0.402042 0.402042)
							(end 0.4318 0.3302)
						)
						(arc
							(start 0.4318 -0.3302)
							(mid 0.402042 -0.402042)
							(end 0.3302 -0.4318)
						)
					)
					(width 0)
					(fill yes)
				)
			)
		)
		(pad "2" smd custom
			(at 0 0.762 270)
			(size 0.2159 0.2159)
			(layers "F.Cu" "F.Mask" "F.Paste")
			(net "P3V3")
			(options
				(clearance outline)
				(anchor circle)
			)
			(primitives
				(gr_poly
					(pts
						(arc
							(start -0.3302 -0.4318)
							(mid -0.402042 -0.402042)
							(end -0.4318 -0.3302)
						)
						(arc
							(start -0.4318 0.3302)
							(mid -0.402042 0.402042)
							(end -0.3302 0.4318)
						)
						(arc
							(start 0.3302 0.4318)
							(mid 0.402042 0.402042)
							(end 0.4318 0.3302)
						)
						(arc
							(start 0.4318 -0.3302)
							(mid 0.402042 -0.402042)
							(end 0.3302 -0.4318)
						)
					)
					(width 0)
					(fill yes)
				)
			)
		)
	)
	(footprint ""
		(layer "F.Cu")
		(at 21.2725 -167.247316 180)
		(property "Reference" "C223"
			(at 0 0 180)
			(layer "F.SilkS")
			(hide yes)
			(effects
				(font
					(size 1.27 1.27)
				)
			)
		)
		(property "Value" "SC10U6D3V5KX-4GP"
			(at -0.0762 -6.1214 180)
			(unlocked yes)
			(layer "F.Fab")
			(hide yes)
			(effects
				(font
					(size 1.016 1.016)
					(thickness 0.1524)
				)
			)
		)
		(property "Device Type" "C805H58"
			(at -0.0762 -8.1534 180)
			(unlocked yes)
			(layer "F.Fab")
			(hide yes)
			(effects
				(font
					(size 1.016 1.016)
					(thickness 0.1524)
				)
			)
		)
		(duplicate_pad_numbers_are_jumpers no)
		(fp_line
			(start 0.635 0)
			(end -0.635 0)
			(stroke
				(width 0.508)
				(type default)
			)
			(layer "F.SilkS")
		)
		(fp_rect
			(start -0.9652 1.778)
			(end 0.9652 -1.778)
			(stroke
				(width 0)
				(type default)
			)
			(fill no)
			(layer "F.CrtYd")
		)
		(fp_poly
			(pts
				(xy -0.9652 -1.778) (xy 0.9652 -1.778) (xy 0.9652 1.778) (xy -0.9652 1.778)
			)
			(stroke
				(width 0)
				(type default)
			)
			(fill no)
			(layer "F.Fab")
		)
		(pad "1" smd rect
			(at 0 -0.9652 180)
			(size 1.397 1.143)
			(layers "F.Cu" "F.Mask" "F.Paste")
			(net "TPS74801_P1V2_STBY_OUT")
		)
		(pad "2" smd rect
			(at 0 0.9652 180)
			(size 1.397 1.143)
			(layers "F.Cu" "F.Mask" "F.Paste")
			(net "GND")
		)
	)
	(footprint ""
		(layer "F.Cu")
		(at 98.922332 -18.402046 90)
		(property "Reference" "L1"
			(at 0 0 90)
			(layer "F.SilkS")
			(hide yes)
			(effects
				(font
					(size 1.27 1.27)
				)
			)
		)
		(property "Value" "DLW21HN900SQ2LGP-U"
			(at -0.0889 -2.7813 90)
			(unlocked yes)
			(layer "F.Fab")
			(hide yes)
			(effects
				(font
					(size 1.016 1.016)
					(thickness 0.1524)
				)
			)
		)
		(property "Device Type" "L2012-4P-1MH40"
			(at -0.0889 -4.3053 90)
			(unlocked yes)
			(layer "F.Fab")
			(hide yes)
			(effects
				(font
					(size 1.016 1.016)
					(thickness 0.1524)
				)
			)
		)
		(duplicate_pad_numbers_are_jumpers no)
		(fp_line
			(start 1.5494 -1.0668)
			(end 1.5494 1.0668)
			(stroke
				(width 0.1524)
				(type default)
			)
			(layer "F.SilkS")
		)
		(fp_line
			(start -1.5494 -1.0668)
			(end 1.5494 -1.0668)
			(stroke
				(width 0.1524)
				(type default)
			)
			(layer "F.SilkS")
		)
		(fp_line
			(start 1.5494 1.0668)
			(end -1.5494 1.0668)
			(stroke
				(width 0.1524)
				(type default)
			)
			(layer "F.SilkS")
		)
		(fp_line
			(start -1.5494 1.0668)
			(end -1.5494 -1.0668)
			(stroke
				(width 0.1524)
				(type default)
			)
			(layer "F.SilkS")
		)
		(fp_line
			(start 1.0668 1.1811)
			(end 0.6858 1.1811)
			(stroke
				(width 0.3302)
				(type default)
			)
			(layer "F.SilkS")
		)
		(fp_poly
			(pts
				(xy 1.500124 1.768856) (xy 0.230124 1.768856) (xy 0.865124 1.133856)
			)
			(stroke
				(width 0)
				(type default)
			)
			(fill yes)
			(layer "F.SilkS")
		)
		(fp_rect
			(start -1.0033 0.5969)
			(end 1.0033 -0.5969)
			(stroke
				(width 0)
				(type default)
			)
			(fill no)
			(layer "F.CrtYd")
		)
		(fp_poly
			(pts
				(xy -1.8034 1.3208) (xy -1.8034 -1.3208) (xy 1.8034 -1.3208) (xy 1.8034 0.0508) (xy 1.0033 0.0508)
				(xy 1.0033 -0.5969) (xy -1.0033 -0.5969) (xy -1.0033 0.5969) (xy 1.0033 0.5969) (xy 1.0033 0.0762)
				(xy 1.8034 0.0762) (xy 1.8034 1.3208)
			)
			(stroke
				(width 0)
				(type default)
			)
			(fill no)
			(layer "F.CrtYd")
		)
		(fp_rect
			(start -1.8034 1.3208)
			(end 1.8034 -1.3208)
			(stroke
				(width 0)
				(type default)
			)
			(fill no)
			(layer "F.Fab")
		)
		(pad "1" smd rect
			(at 0.8382 0.4826 90)
			(size 0.9144 0.6604)
			(layers "F.Cu" "F.Mask" "F.Paste")
			(net "USB_P1_DP")
		)
		(pad "2" smd rect
			(at -0.8382 0.4826 90)
			(size 0.9144 0.6604)
			(layers "F.Cu" "F.Mask" "F.Paste")
			(net "USB_P1_F_DP1")
		)
		(pad "3" smd rect
			(at -0.8382 -0.4826 90)
			(size 0.9144 0.6604)
			(layers "F.Cu" "F.Mask" "F.Paste")
			(net "USB_P1_F_DN1")
		)
		(pad "4" smd rect
			(at 0.8382 -0.4826 90)
			(size 0.9144 0.6604)
			(layers "F.Cu" "F.Mask" "F.Paste")
			(net "USB_P1_DN")
		)
		(zone
			(layer "F.Cu")
			(hatch none 0.5)
			(connect_pads
				(clearance 0)
			)
			(min_thickness 0.25)
			(keepout
				(tracks allowed)
				(vias not_allowed)
				(pads allowed)
				(copperpour not_allowed)
				(footprints allowed)
			)
			(placement
				(enabled no)
				(sheetname "")
			)
			(fill
				(thermal_gap 0.5)
				(thermal_bridge_width 0.5)
				(island_removal_mode 0)
			)
			(polygon
				(pts
					(xy 99.735132 -18.021046) (xy 99.074732 -18.021046) (xy 99.074732 -17.106646) (xy 98.769932 -17.106646)
					(xy 98.769932 -18.021046) (xy 98.109532 -18.021046) (xy 98.109532 -18.783046) (xy 98.769932 -18.783046)
					(xy 98.769932 -19.697446) (xy 99.074732 -19.697446) (xy 99.074732 -18.783046) (xy 99.735132 -18.783046)
				)
			)
		)
		(zone
			(layer "F.Cu")
			(hatch none 0.5)
			(connect_pads
				(clearance 0)
			)
			(min_thickness 0.25)
			(keepout
				(tracks not_allowed)
				(vias allowed)
				(pads allowed)
				(copperpour not_allowed)
				(footprints allowed)
			)
			(placement
				(enabled no)
				(sheetname "")
			)
			(fill
				(thermal_gap 0.5)
				(thermal_bridge_width 0.5)
				(island_removal_mode 0)
			)
			(polygon
				(pts
					(xy 99.735132 -18.021046) (xy 99.074732 -18.021046) (xy 99.074732 -17.106646) (xy 98.769932 -17.106646)
					(xy 98.769932 -18.021046) (xy 98.109532 -18.021046) (xy 98.109532 -18.783046) (xy 98.769932 -18.783046)
					(xy 98.769932 -19.697446) (xy 99.074732 -19.697446) (xy 99.074732 -18.783046) (xy 99.735132 -18.783046)
				)
			)
		)
	)
	(footprint ""
		(layer "F.Cu")
		(at 84.438744 -160.351216 180)
		(property "Reference" "C237"
			(at 0 0 180)
			(layer "F.SilkS")
			(hide yes)
			(effects
				(font
					(size 1.27 1.27)
				)
			)
		)
		(property "Value" "SC10U6D3V5KX-4GP"
			(at -0.0762 -6.1214 180)
			(unlocked yes)
			(layer "F.Fab")
			(hide yes)
			(effects
				(font
					(size 1.016 1.016)
					(thickness 0.1524)
				)
			)
		)
		(property "Device Type" "C805H58"
			(at -0.0762 -8.1534 180)
			(unlocked yes)
			(layer "F.Fab")
			(hide yes)
			(effects
				(font
					(size 1.016 1.016)
					(thickness 0.1524)
				)
			)
		)
		(duplicate_pad_numbers_are_jumpers no)
		(fp_line
			(start 0.635 0)
			(end -0.635 0)
			(stroke
				(width 0.508)
				(type default)
			)
			(layer "F.SilkS")
		)
		(fp_rect
			(start -0.9652 1.778)
			(end 0.9652 -1.778)
			(stroke
				(width 0)
				(type default)
			)
			(fill no)
			(layer "F.CrtYd")
		)
		(fp_poly
			(pts
				(xy -0.9652 -1.778) (xy 0.9652 -1.778) (xy 0.9652 1.778) (xy -0.9652 1.778)
			)
			(stroke
				(width 0)
				(type default)
			)
			(fill no)
			(layer "F.Fab")
		)
		(pad "1" smd rect
			(at 0 -0.9652 180)
			(size 1.397 1.143)
			(layers "F.Cu" "F.Mask" "F.Paste")
			(net "TPS74801_P1V15_STBY_OUT")
		)
		(pad "2" smd rect
			(at 0 0.9652 180)
			(size 1.397 1.143)
			(layers "F.Cu" "F.Mask" "F.Paste")
			(net "GND")
		)
	)
)
